(kicad_pcb
	(version 20260206)
	(generator "pcbnew")
	(generator_version "10.0")
	(general
		(thickness 1.6)
		(legacy_teardrops no)
	)
	(paper "A4")
	(title_block
		(title "01162023_DA0F0TEBIF0_F0T_Expander_BD_F_brd_V02_OCP.brd")
		(comment 1 "Grand Teton / footprint 1849 of 9728 (U5), pads 224-256 of 256")
	)
	(layers
		(0 "F.Cu" signal "TOP")
		(4 "In1.Cu" signal "GND")
		(6 "In2.Cu" signal "VCC")
		(8 "In3.Cu" signal "VCC1")
		(10 "In4.Cu" signal "GND1")
		(12 "In5.Cu" signal "IN1")
		(14 "In6.Cu" signal "GND2")
		(16 "In7.Cu" signal "IN2")
		(18 "In8.Cu" signal "GND3")
		(20 "In9.Cu" signal "IN3")
		(22 "In10.Cu" signal "GND4")
		(24 "In11.Cu" signal "IN4")
		(26 "In12.Cu" signal "GND5")
		(28 "In13.Cu" signal "IN5")
		(30 "In14.Cu" signal "GND6")
		(32 "In15.Cu" signal "IN6")
		(34 "In16.Cu" signal "GND7")
		(2 "B.Cu" signal "BOTTOM")
		(9 "F.Adhes" user "F.Adhesive")
		(11 "B.Adhes" user "B.Adhesive")
		(13 "F.Paste" user "Package Geometry/Pastemask Top")
		(15 "B.Paste" user "Package Geometry/Pastemask Bottom")
		(5 "F.SilkS" user "Ref Des/Silkscreen Top")
		(7 "B.SilkS" user "Ref Des/Silkscreen Bottom")
		(1 "F.Mask" user "Board Geometry/Soldermask Top")
		(3 "B.Mask" user "Board Geometry/Soldermask Bottom")
		(17 "Dwgs.User" user "User.Drawings")
		(19 "Cmts.User" user "User.Comments")
		(21 "Eco1.User" user "User.Eco1")
		(23 "Eco2.User" user "User.Eco2")
		(25 "Edge.Cuts" user "Board Geometry/Outline")
		(27 "Margin" user)
		(31 "F.CrtYd" user "Package Geometry/Place Bound Top")
		(29 "B.CrtYd" user "Package Geometry/Place Bound Bottom")
		(35 "F.Fab" user "Ref Des/Assembly Top")
		(33 "B.Fab" user "Ref Des/Assembly Bottom")
	)
	(footprint ""
		(layer "F.Cu")
		(at 229.467664 -218.70416 180)
		(property "Reference" "U5"
			(at -4.517136 -8.03783 0)
			(unlocked yes)
			(layer "F.SilkS")
			(effects
				(font
					(size 0.7874 0.5842)
					(thickness 0.1524)
				)
				(justify left)
			)
		)
		(property "Value" ""
			(at 0 0 180)
			(layer "F.Fab")
			(effects
				(font
					(size 1.27 1.27)
				)
			)
		)
		(duplicate_pad_numbers_are_jumpers no)
		(pad "P16" smd circle
			(at 5.999988 4.400042 180)
			(size 0.4064 0.4064)
			(layers "F.Cu" "F.Mask" "F.Paste")
			(net "SMB_NIC3_SDA")
		)
		(pad "R1" smd circle
			(at -5.999988 5.199888 180)
			(size 0.4064 0.4064)
			(layers "F.Cu" "F.Mask" "F.Paste")
			(net "PRSNT_NIC6_R_N")
		)
		(pad "R2" smd circle
			(at -5.199888 5.199888 180)
			(size 0.4064 0.4064)
			(layers "F.Cu" "F.Mask" "F.Paste")
			(net "PRSNT_NIC7_R_N")
		)
		(pad "R3" smd circle
			(at -4.400042 5.199888 180)
			(size 0.4064 0.4064)
			(layers "F.Cu" "F.Mask" "F.Paste")
			(net "PRSNT_SSD1_R_N")
		)
		(pad "R4" smd circle
			(at -3.599942 5.199888 180)
			(size 0.4064 0.4064)
			(layers "F.Cu" "F.Mask" "F.Paste")
			(net "PRSNT_SSD7_R_N")
		)
		(pad "R5" smd circle
			(at -2.800096 5.199888 180)
			(size 0.4064 0.4064)
			(layers "F.Cu" "F.Mask" "F.Paste")
			(net "SSD0_PWRDIS_BIC")
		)
		(pad "R6" smd circle
			(at -1.999996 5.199888 180)
			(size 0.4064 0.4064)
			(layers "F.Cu" "F.Mask" "F.Paste")
			(net "SSD6_PWRDIS_BIC")
		)
		(pad "R7" smd circle
			(at -1.199896 5.199888 180)
			(size 0.4064 0.4064)
			(layers "F.Cu" "F.Mask" "F.Paste")
			(net "SSD8_PWRDIS_BIC")
		)
		(pad "R8" smd circle
			(at -0.40005 5.199888 180)
			(size 0.4064 0.4064)
			(layers "F.Cu" "F.Mask" "F.Paste")
			(net "SSD10_PWRDIS_BIC")
		)
		(pad "R9" smd circle
			(at 0.40005 5.199888 180)
			(size 0.4064 0.4064)
			(layers "F.Cu" "F.Mask" "F.Paste")
			(net "NIC2_MAIN_PWR_BIC_EN")
		)
		(pad "R10" smd circle
			(at 1.199896 5.199888 180)
			(size 0.4064 0.4064)
			(layers "F.Cu" "F.Mask" "F.Paste")
			(net "NIC4_MAIN_PWR_BIC_EN")
		)
		(pad "R11" smd circle
			(at 1.999996 5.199888 180)
			(size 0.4064 0.4064)
			(layers "F.Cu" "F.Mask" "F.Paste")
			(net "REV_ID0")
		)
		(pad "R12" smd circle
			(at 2.800096 5.199888 180)
			(size 0.4064 0.4064)
			(layers "F.Cu" "F.Mask" "F.Paste")
			(net "REV_ID2")
		)
		(pad "R13" smd circle
			(at 3.599942 5.199888 180)
			(size 0.4064 0.4064)
			(layers "F.Cu" "F.Mask" "F.Paste")
			(net "BOARD_ID2")
		)
		(pad "R14" smd circle
			(at 4.400042 5.199888 180)
			(size 0.4064 0.4064)
			(layers "F.Cu" "F.Mask" "F.Paste")
			(net "HSC_UV_R_N")
		)
		(pad "R15" smd circle
			(at 5.199888 5.199888 180)
			(size 0.4064 0.4064)
			(layers "F.Cu" "F.Mask" "F.Paste")
			(net "SMB_NIC0_SCL")
		)
		(pad "R16" smd circle
			(at 5.999988 5.199888 180)
			(size 0.4064 0.4064)
			(layers "F.Cu" "F.Mask" "F.Paste")
			(net "SMB_NIC2_SDA")
		)
		(pad "T1" smd circle
			(at -5.999988 5.999988 180)
			(size 0.4064 0.4064)
			(layers "F.Cu" "F.Mask" "F.Paste")
			(net "PRSNT_SSD0_R_N")
		)
		(pad "T2" smd circle
			(at -5.199888 5.999988 180)
			(size 0.4064 0.4064)
			(layers "F.Cu" "F.Mask" "F.Paste")
			(net "PRSNT_SSD2_R_N")
		)
		(pad "T3" smd circle
			(at -4.400042 5.999988 180)
			(size 0.4064 0.4064)
			(layers "F.Cu" "F.Mask" "F.Paste")
			(net "PRSNT_SSD3_R_N")
		)
		(pad "T4" smd circle
			(at -3.599942 5.999988 180)
			(size 0.4064 0.4064)
			(layers "F.Cu" "F.Mask" "F.Paste")
			(net "SSD1_PWRDIS_BIC")
		)
		(pad "T5" smd circle
			(at -2.800096 5.999988 180)
			(size 0.4064 0.4064)
			(layers "F.Cu" "F.Mask" "F.Paste")
			(net "SSD5_PWRDIS_BIC")
		)
		(pad "T6" smd circle
			(at -1.999996 5.999988 180)
			(size 0.4064 0.4064)
			(layers "F.Cu" "F.Mask" "F.Paste")
			(net "SSD7_PWRDIS_BIC")
		)
		(pad "T7" smd circle
			(at -1.199896 5.999988 180)
			(size 0.4064 0.4064)
			(layers "F.Cu" "F.Mask" "F.Paste")
			(net "SSD9_PWRDIS_BIC")
		)
		(pad "T8" smd circle
			(at -0.40005 5.999988 180)
			(size 0.4064 0.4064)
			(layers "F.Cu" "F.Mask" "F.Paste")
			(net "SSD11_PWRDIS_BIC")
		)
		(pad "T9" smd circle
			(at 0.40005 5.999988 180)
			(size 0.4064 0.4064)
			(layers "F.Cu" "F.Mask" "F.Paste")
			(net "NIC0_MAIN_PWR_BIC_EN")
		)
		(pad "T10" smd circle
			(at 1.199896 5.999988 180)
			(size 0.4064 0.4064)
			(layers "F.Cu" "F.Mask" "F.Paste")
			(net "NIC3_MAIN_PWR_BIC_EN")
		)
		(pad "T11" smd circle
			(at 1.999996 5.999988 180)
			(size 0.4064 0.4064)
			(layers "F.Cu" "F.Mask" "F.Paste")
			(net "NIC6_MAIN_PWR_BIC_EN")
		)
		(pad "T12" smd circle
			(at 2.800096 5.999988 180)
			(size 0.4064 0.4064)
			(layers "F.Cu" "F.Mask" "F.Paste")
			(net "REV_ID1")
		)
		(pad "T13" smd circle
			(at 3.599942 5.999988 180)
			(size 0.4064 0.4064)
			(layers "F.Cu" "F.Mask" "F.Paste")
			(net "BOARD_ID0")
		)
		(pad "T14" smd circle
			(at 4.400042 5.999988 180)
			(size 0.4064 0.4064)
			(layers "F.Cu" "F.Mask" "F.Paste")
			(net "HSC_TIMER_N")
		)
		(pad "T15" smd circle
			(at 5.199888 5.999988 180)
			(size 0.4064 0.4064)
			(layers "F.Cu" "F.Mask" "F.Paste")
			(net "HSC_D_OC_BIC_N")
		)
		(pad "T16" smd circle
			(at 5.999988 5.999988 180)
			(size 0.4064 0.4064)
			(layers "F.Cu" "F.Mask" "F.Paste")
			(net "SMB_NIC2_SCL")
		)
	)
)
